# S9S_MB_2U (Grand Teton) — schematic netlist excerpt (pin names and nets, part order shuffled) for the footprints in the layout excerpt that follows; sources: Cadence DE-HDL packaged netlist, KiCad conversion of 03242023_DA0F0TMBIJ0_F0T_Motherboard_J_brd_V01_OCP.brd

U248  74LVC1G32GW  IC  pkg SMLF  page 212
  I0  = GPU_FPGA_READY_R_N
  I1  = CLK_GEN2_GPU_FPGA_OE_R2_N
  GND  = GND
  O  = CLK_GEN2_GPU_FPGA_OE_OR_N
  VCC  = P3V3_AUX

Q33  MOSFET_NCH_GDS_ESD_PROTECTED  2N7002K IC  pkg SOT23_GDSXC  page 218
  D  = LED_CPU_RMCA_CATERR
  G  = CPU_RMCA_CATERR_LVT3_N
  S  = LED_CPU_RMCA_CATERR_R

(kicad_pcb
	(version 20260206)
	(generator "pcbnew")
	(generator_version "10.0")
	(general
		(thickness 1.6)
		(legacy_teardrops no)
	)
	(paper "A4")
	(title_block
		(title "03242023_DA0F0TMBIJ0_F0T_Motherboard_J_brd_V01_OCP.brd")
		(comment 1 "Grand Teton / footprints 3868-3869 of 6105")
	)
	(layers
		(0 "F.Cu" signal "TOP")
		(4 "In1.Cu" signal "GND")
		(6 "In2.Cu" signal "IN1")
		(8 "In3.Cu" signal "GND1")
		(10 "In4.Cu" signal "IN2")
		(12 "In5.Cu" signal "GND2")
		(14 "In6.Cu" signal "IN3")
		(16 "In7.Cu" signal "GND3")
		(18 "In8.Cu" signal "VCC")
		(20 "In9.Cu" signal "VCC1")
		(22 "In10.Cu" signal "GND4")
		(24 "In11.Cu" signal "IN4")
		(26 "In12.Cu" signal "GND5")
		(28 "In13.Cu" signal "IN5")
		(30 "In14.Cu" signal "GND6")
		(32 "In15.Cu" signal "IN6")
		(34 "In16.Cu" signal "GND7")
		(2 "B.Cu" signal "BOTTOM")
		(9 "F.Adhes" user "F.Adhesive")
		(11 "B.Adhes" user "B.Adhesive")
		(13 "F.Paste" user "Package Geometry/Pastemask Top")
		(15 "B.Paste" user "Package Geometry/Pastemask Bottom")
		(5 "F.SilkS" user "Ref Des/Silkscreen Top")
		(7 "B.SilkS" user "Ref Des/Silkscreen Bottom")
		(1 "F.Mask" user "Board Geometry/Soldermask Top")
		(3 "B.Mask" user "Board Geometry/Soldermask Bottom")
		(17 "Dwgs.User" user "User.Drawings")
		(19 "Cmts.User" user "User.Comments")
		(21 "Eco1.User" user "User.Eco1")
		(23 "Eco2.User" user "User.Eco2")
		(25 "Edge.Cuts" user "Board Geometry/Outline")
		(27 "Margin" user)
		(31 "F.CrtYd" user "Package Geometry/Place Bound Top")
		(29 "B.CrtYd" user "Package Geometry/Place Bound Bottom")
		(35 "F.Fab" user "Ref Des/Assembly Top")
		(33 "B.Fab" user "Ref Des/Assembly Bottom")
	)
	(footprint ""
		(layer "F.Cu")
		(at 205.54188 -109.057948 90)
		(property "Reference" "Q33"
			(at 1.09601 -4.26466 0)
			(unlocked yes)
			(layer "F.SilkS")
			(effects
				(font
					(size 0.7874 0.5842)
					(thickness 0.1524)
				)
				(justify left)
			)
		)
		(property "Value" ""
			(at 0 0 90)
			(layer "F.Fab")
			(effects
				(font
					(size 1.27 1.27)
				)
			)
		)
		(duplicate_pad_numbers_are_jumpers no)
		(fp_line
			(start 1.603248 -1.500124)
			(end 1.603248 1.500124)
			(stroke
				(width 0.1524)
				(type default)
			)
			(layer "F.SilkS")
		)
		(fp_line
			(start -1.603248 -1.500124)
			(end 1.603248 -1.500124)
			(stroke
				(width 0.1524)
				(type default)
			)
			(layer "F.SilkS")
		)
		(fp_line
			(start 1.603248 1.500124)
			(end -1.603248 1.500124)
			(stroke
				(width 0.1524)
				(type default)
			)
			(layer "F.SilkS")
		)
		(fp_line
			(start -1.603248 1.500124)
			(end -1.603248 -1.500124)
			(stroke
				(width 0.1524)
				(type default)
			)
			(layer "F.SilkS")
		)
		(fp_line
			(start 0.700024 -1.500124)
			(end -0.700024 -1.500124)
			(stroke
				(width 0.1)
				(type default)
			)
			(layer "F.Fab")
		)
		(fp_line
			(start -0.700024 -1.500124)
			(end -0.700024 -1.169924)
			(stroke
				(width 0.1)
				(type default)
			)
			(layer "F.Fab")
		)
		(fp_line
			(start -0.700024 -1.169924)
			(end -1.249934 -1.169924)
			(stroke
				(width 0.1)
				(type default)
			)
			(layer "F.Fab")
		)
		(fp_line
			(start -1.249934 -1.169924)
			(end -1.249934 -0.729996)
			(stroke
				(width 0.1)
				(type default)
			)
			(layer "F.Fab")
		)
		(fp_line
			(start -0.6985 -0.729996)
			(end -0.6985 0.729996)
			(stroke
				(width 0.1)
				(type default)
			)
			(layer "F.Fab")
		)
		(fp_line
			(start -1.249934 -0.729996)
			(end -0.6985 -0.729996)
			(stroke
				(width 0.1)
				(type default)
			)
			(layer "F.Fab")
		)
		(fp_line
			(start 1.249934 -0.219964)
			(end 0.700024 -0.219964)
			(stroke
				(width 0.1)
				(type default)
			)
			(layer "F.Fab")
		)
		(fp_line
			(start 0.700024 -0.219964)
			(end 0.700024 -1.500124)
			(stroke
				(width 0.1)
				(type default)
			)
			(layer "F.Fab")
		)
		(fp_line
			(start 1.249934 0.219964)
			(end 1.249934 -0.219964)
			(stroke
				(width 0.1)
				(type default)
			)
			(layer "F.Fab")
		)
		(fp_line
			(start 0.700024 0.219964)
			(end 1.249934 0.219964)
			(stroke
				(width 0.1)
				(type default)
			)
			(layer "F.Fab")
		)
		(fp_line
			(start -0.6985 0.729996)
			(end -1.249934 0.729996)
			(stroke
				(width 0.1)
				(type default)
			)
			(layer "F.Fab")
		)
		(fp_line
			(start -1.249934 0.729996)
			(end -1.249934 1.169924)
			(stroke
				(width 0.1)
				(type default)
			)
			(layer "F.Fab")
		)
		(fp_line
			(start -0.700024 1.169924)
			(end -0.700024 1.500124)
			(stroke
				(width 0.1)
				(type default)
			)
			(layer "F.Fab")
		)
		(fp_line
			(start -1.249934 1.169924)
			(end -0.700024 1.169924)
			(stroke
				(width 0.1)
				(type default)
			)
			(layer "F.Fab")
		)
		(fp_line
			(start 0.700024 1.500124)
			(end 0.700024 0.219964)
			(stroke
				(width 0.1)
				(type default)
			)
			(layer "F.Fab")
		)
		(fp_line
			(start -0.700024 1.500124)
			(end 0.700024 1.500124)
			(stroke
				(width 0.1)
				(type default)
			)
			(layer "F.Fab")
		)
		(fp_rect
			(start -0.700024 -1.500124)
			(end 0.700024 1.500124)
			(stroke
				(width 0)
				(type default)
			)
			(fill no)
			(layer "F.Fab")
		)
		(pad "D" smd rect
			(at 0.999998 0)
			(size 0.8128 0.9144)
			(layers "F.Cu" "F.Mask" "F.Paste")
			(net "LED_CPU_RMCA_CATERR")
		)
		(pad "G" smd rect
			(at -0.999998 -0.94996)
			(size 0.8128 0.9144)
			(layers "F.Cu" "F.Mask" "F.Paste")
			(net "CPU_RMCA_CATERR_LVT3_N")
		)
		(pad "S" smd rect
			(at -0.999998 0.94996)
			(size 0.8128 0.9144)
			(layers "F.Cu" "F.Mask" "F.Paste")
			(net "LED_CPU_RMCA_CATERR_R")
		)
	)
	(footprint ""
		(layer "F.Cu")
		(at 120.603264 -38.005512)
		(property "Reference" "U248"
			(at -1.48336 1.88849 0)
			(unlocked yes)
			(layer "F.SilkS")
			(effects
				(font
					(size 0.7874 0.5842)
					(thickness 0.1524)
				)
				(justify left)
			)
		)
		(property "Value" ""
			(at 0 0 0)
			(layer "F.Fab")
			(effects
				(font
					(size 1.27 1.27)
				)
			)
		)
		(duplicate_pad_numbers_are_jumpers no)
		(fp_line
			(start -1.4986 -1.100074)
			(end 1.4986 -1.100074)
			(stroke
				(width 0.1524)
				(type default)
			)
			(layer "F.SilkS")
		)
		(fp_line
			(start -1.4986 1.100074)
			(end -1.4986 -1.100074)
			(stroke
				(width 0.1524)
				(type default)
			)
			(layer "F.SilkS")
		)
		(fp_line
			(start 1.4986 -1.100074)
			(end 1.4986 1.100074)
			(stroke
				(width 0.1524)
				(type default)
			)
			(layer "F.SilkS")
		)
		(fp_line
			(start 1.4986 1.100074)
			(end -1.4986 1.100074)
			(stroke
				(width 0.1524)
				(type default)
			)
			(layer "F.SilkS")
		)
		(fp_poly
			(pts
				(xy -0.715772 -1.863852) (xy -1.04394 -1.310132) (xy -1.340612 -1.863852)
			)
			(stroke
				(width 0)
				(type default)
			)
			(fill yes)
			(layer "F.SilkS")
		)
		(fp_line
			(start -0.67437 -1.100074)
			(end 0.67437 -1.100074)
			(stroke
				(width 0.1)
				(type default)
			)
			(layer "F.Fab")
		)
		(fp_line
			(start -0.67437 1.100074)
			(end -0.67437 -1.100074)
			(stroke
				(width 0.1)
				(type default)
			)
			(layer "F.Fab")
		)
		(fp_line
			(start 0.67437 -1.100074)
			(end 0.67437 1.100074)
			(stroke
				(width 0.1)
				(type default)
			)
			(layer "F.Fab")
		)
		(fp_line
			(start 0.67437 1.100074)
			(end -0.67437 1.100074)
			(stroke
				(width 0.1)
				(type default)
			)
			(layer "F.Fab")
		)
		(fp_poly
			(pts
				(xy -2.20472 -0.338328) (xy -2.20472 -0.963168) (xy -1.651 -0.635)
			)
			(stroke
				(width 0)
				(type default)
			)
			(fill yes)
			(layer "F.Fab")
		)
		(pad "1" smd rect
			(at -0.889 -0.649986)
			(size 1.016 0.381)
			(layers "F.Cu" "F.Mask" "F.Paste")
			(net "GPU_FPGA_READY_R_N")
		)
		(pad "2" smd rect
			(at -0.889 0)
			(size 1.016 0.381)
			(layers "F.Cu" "F.Mask" "F.Paste")
			(net "CLK_GEN2_GPU_FPGA_OE_R2_N")
		)
		(pad "3" smd rect
			(at -0.889 0.649986)
			(size 1.016 0.381)
			(layers "F.Cu" "F.Mask" "F.Paste")
			(net "GND")
		)
		(pad "4" smd rect
			(at 0.889 0.649986)
			(size 1.016 0.381)
			(layers "F.Cu" "F.Mask" "F.Paste")
			(net "CLK_GEN2_GPU_FPGA_OE_OR_N")
		)
		(pad "5" smd rect
			(at 0.889 -0.649986)
			(size 1.016 0.381)
			(layers "F.Cu" "F.Mask" "F.Paste")
			(net "P3V3_AUX")
		)
	)
)
